FILE_TYPE = MACRO_DRAWING;
SET COLOR_WIRE YELLOW;
SET COLOR_PROP ORANGE;
SET COLOR_DOT WHITE;
SET COLOR_ARC YELLOW;
SET COLOR_BODY GREEN;
SET COLOR_NOTE PURPLE;
SET PROP_DISPLAY VALUE;
SET PAGE_NUMBER P394;
FORCEADD PT5161LRS..1
(-7525 3875);
FORCEPROP 1 LAST LOCATION U6015
J 0
(-7875 5500);
DISPLAY 0.723404 (-7875 5500);
PAINT GREEN (-7875 5500);
FORCEPROP 0 LAST $SEC 1
J 0
(-7875 5650);
DISPLAY 0.680851 (-7875 5650);
PAINT MONO (-7875 5650);
DISPLAY INVISIBLE (-7875 5650);
FORCEPROP 0 LAST CDS_SEC 1
J 0
(-7875 5650);
DISPLAY 0.680851 (-7875 5650);
DISPLAY INVISIBLE (-7875 5650);
FORCEPROP 0 LASTPIN (-7075 5025) $PN N2
J 0
(-7065 5035);
DISPLAY 0.680851 (-7065 5035);
PAINT MONO (-7065 5035);
FORCEPROP 0 LASTPIN (-7075 4675) $PN Y2
J 0
(-7065 4685);
DISPLAY 0.680851 (-7065 4685);
PAINT MONO (-7065 4685);
FORCEPROP 0 LASTPIN (-7075 4325) $PN AG2
J 0
(-7065 4335);
DISPLAY 0.680851 (-7065 4335);
PAINT MONO (-7065 4335);
FORCEPROP 0 LASTPIN (-7075 3975) $PN AP2
J 0
(-7065 3985);
DISPLAY 0.680851 (-7065 3985);
PAINT MONO (-7065 3985);
FORCEPROP 0 LASTPIN (-7075 3625) $PN BA2
J 0
(-7065 3635);
DISPLAY 0.680851 (-7065 3635);
PAINT MONO (-7065 3635);
FORCEPROP 0 LASTPIN (-7075 3275) $PN BH2
J 0
(-7065 3285);
DISPLAY 0.680851 (-7065 3285);
PAINT MONO (-7065 3285);
FORCEPROP 0 LASTPIN (-7075 2925) $PN BR2
J 0
(-7065 2935);
DISPLAY 0.680851 (-7065 2935);
PAINT MONO (-7065 2935);
FORCEPROP 0 LASTPIN (-7075 2575) $PN CB2
J 0
(-7065 2585);
DISPLAY 0.680851 (-7065 2585);
PAINT MONO (-7065 2585);
FORCEPROP 0 LASTPIN (-7075 5125) $PN R1
J 0
(-7065 5135);
DISPLAY 0.680851 (-7065 5135);
PAINT MONO (-7065 5135);
FORCEPROP 0 LASTPIN (-7075 4775) $PN AB1
J 0
(-7065 4785);
DISPLAY 0.680851 (-7065 4785);
PAINT MONO (-7065 4785);
FORCEPROP 0 LASTPIN (-7075 4425) $PN AJ1
J 0
(-7065 4435);
DISPLAY 0.680851 (-7065 4435);
PAINT MONO (-7065 4435);
FORCEPROP 0 LASTPIN (-7075 4075) $PN AT1
J 0
(-7065 4085);
DISPLAY 0.680851 (-7065 4085);
PAINT MONO (-7065 4085);
FORCEPROP 0 LASTPIN (-7075 3725) $PN BC1
J 0
(-7065 3735);
DISPLAY 0.680851 (-7065 3735);
PAINT MONO (-7065 3735);
FORCEPROP 0 LASTPIN (-7075 3375) $PN BK1
J 0
(-7065 3385);
DISPLAY 0.680851 (-7065 3385);
PAINT MONO (-7065 3385);
FORCEPROP 0 LASTPIN (-7075 3025) $PN BU1
J 0
(-7065 3035);
DISPLAY 0.680851 (-7065 3035);
PAINT MONO (-7065 3035);
FORCEPROP 0 LASTPIN (-7075 2675) $PN CD1
J 0
(-7065 2685);
DISPLAY 0.680851 (-7065 2685);
PAINT MONO (-7065 2685);
FORCEPROP 2 LAST PART_TYPE SMLF
J 0
(-7875 5600);
DISPLAY 0.680851 (-7875 5600);
FORCEPROP 1 LAST MATERIAL IC
J 0
(-7875 5350);
DISPLAY 0.723404 (-7875 5350);
PAINT GREEN (-7875 5350);
FORCEPROP 2 LAST VALUE PT5161LRS
J 0
(-7875 5550);
DISPLAY 0.680851 (-7875 5550);
FORCEPROP 2 LAST CDS_LIB pure_quanta
J 0
(-7525 3875);
DISPLAY INVISIBLE (-7525 3875);
FORCEPROP 1 LAST CDS_LMAN_SYM_OUTLINE -350,1450,300,-1400
J 0
(-7525 3875);
DISPLAY 0.468085 (-7525 3875);
PAINT GREEN (-7525 3875);
DISPLAY INVISIBLE (-7525 3875);
FORCEPROP 1 LAST NEEDS_NO_SIZE TRUE
J 0
(-7525 3875);
DISPLAY 0.723404 (-7525 3875);
PAINT GREEN (-7525 3875);
DISPLAY INVISIBLE (-7525 3875);
FORCEPROP 1 LAST PATH I1
J 0
(-7525 3875);
DISPLAY 0.723404 (-7525 3875);
PAINT GREEN (-7525 3875);
DISPLAY INVISIBLE (-7525 3875);
FORCEPROP 1 LAST PART_NUMBER AJ051610U03
J 0
(-7875 5425);
DISPLAY 0.723404 (-7875 5425);
PAINT GREEN (-7875 5425);
DISPLAY INVISIBLE (-7875 5425);
FORCEADD TAP..1
(-6300 3625);
FORCEPROP 3 LASTPIN (-6350 3625) SIG_NAME P5E_CPU1_P1_RX_BUF_DN<11>
J 0
(-6340 3635);
DISPLAY 0.659574 (-6340 3635);
PAINT MONO (-6340 3635);
DISPLAY INVISIBLE (-6340 3635);
FORCEPROP 1 LASTPIN (-6350 3625) BN 11
J 0
(-6362 3633);
DISPLAY 0.680851 (-6362 3633);
PAINT GREEN (-6362 3633);
FORCEPROP 2 LAST CDS_LIB standard
J 0
(-6300 3625);
DISPLAY INVISIBLE (-6300 3625);
FORCEPROP 1 LAST BODY_TYPE PLUMBING
J 0
(-6300 3675);
DISPLAY 0.872340 (-6300 3675);
PAINT GREEN (-6300 3675);
DISPLAY INVISIBLE (-6300 3675);
FORCEPROP 1 LAST HDL_TAP TRUE
J 0
(-5975 3500);
DISPLAY 0.872340 (-5975 3500);
DISPLAY INVISIBLE (-5975 3500);
FORCEPROP 1 LAST PATH I10
J 0
(-6302 3625);
DISPLAY 0.872340 (-6302 3625);
PAINT GREEN (-6302 3625);
DISPLAY INVISIBLE (-6302 3625);
FORCEADD TAP..1
(-6300 3975);
FORCEPROP 3 LASTPIN (-6350 3975) SIG_NAME P5E_CPU1_P1_RX_BUF_DN<12>
J 0
(-6340 3985);
DISPLAY 0.659574 (-6340 3985);
PAINT MONO (-6340 3985);
DISPLAY INVISIBLE (-6340 3985);
FORCEPROP 1 LASTPIN (-6350 3975) BN 12
J 0
(-6362 3983);
DISPLAY 0.680851 (-6362 3983);
PAINT GREEN (-6362 3983);
FORCEPROP 2 LAST CDS_LIB standard
J 0
(-6300 3975);
DISPLAY INVISIBLE (-6300 3975);
FORCEPROP 1 LAST BODY_TYPE PLUMBING
J 0
(-6300 4025);
DISPLAY 0.872340 (-6300 4025);
PAINT GREEN (-6300 4025);
DISPLAY INVISIBLE (-6300 4025);
FORCEPROP 1 LAST HDL_TAP TRUE
J 0
(-5975 3850);
DISPLAY 0.872340 (-5975 3850);
DISPLAY INVISIBLE (-5975 3850);
FORCEPROP 1 LAST PATH I11
J 0
(-6302 3975);
DISPLAY 0.872340 (-6302 3975);
PAINT GREEN (-6302 3975);
DISPLAY INVISIBLE (-6302 3975);
FORCEADD TAP..1
(-6500 5125);
FORCEPROP 3 LASTPIN (-6550 5125) SIG_NAME P5E_CPU1_P1_RX_BUF_DP<15>
J 0
(-6540 5135);
DISPLAY 0.659574 (-6540 5135);
PAINT MONO (-6540 5135);
DISPLAY INVISIBLE (-6540 5135);
FORCEPROP 1 LASTPIN (-6550 5125) BN 15
J 0
(-6562 5133);
DISPLAY 0.680851 (-6562 5133);
PAINT GREEN (-6562 5133);
FORCEPROP 2 LAST CDS_LIB standard
J 0
(-6500 5125);
DISPLAY INVISIBLE (-6500 5125);
FORCEPROP 1 LAST BODY_TYPE PLUMBING
J 0
(-6500 5175);
DISPLAY 0.872340 (-6500 5175);
PAINT GREEN (-6500 5175);
DISPLAY INVISIBLE (-6500 5175);
FORCEPROP 1 LAST HDL_TAP TRUE
J 0
(-6175 5000);
DISPLAY 0.872340 (-6175 5000);
DISPLAY INVISIBLE (-6175 5000);
FORCEPROP 1 LAST PATH I12
J 0
(-6502 5125);
DISPLAY 0.872340 (-6502 5125);
PAINT GREEN (-6502 5125);
DISPLAY INVISIBLE (-6502 5125);
FORCEADD TAP..1
(-6500 4775);
FORCEPROP 3 LASTPIN (-6550 4775) SIG_NAME P5E_CPU1_P1_RX_BUF_DP<14>
J 0
(-6540 4785);
DISPLAY 0.659574 (-6540 4785);
PAINT MONO (-6540 4785);
DISPLAY INVISIBLE (-6540 4785);
FORCEPROP 1 LASTPIN (-6550 4775) BN 14
J 0
(-6562 4783);
DISPLAY 0.680851 (-6562 4783);
PAINT GREEN (-6562 4783);
FORCEPROP 2 LAST CDS_LIB standard
J 0
(-6500 4775);
DISPLAY INVISIBLE (-6500 4775);
FORCEPROP 1 LAST BODY_TYPE PLUMBING
J 0
(-6500 4825);
DISPLAY 0.872340 (-6500 4825);
PAINT GREEN (-6500 4825);
DISPLAY INVISIBLE (-6500 4825);
FORCEPROP 1 LAST HDL_TAP TRUE
J 0
(-6175 4650);
DISPLAY 0.872340 (-6175 4650);
DISPLAY INVISIBLE (-6175 4650);
FORCEPROP 1 LAST PATH I13
J 0
(-6502 4775);
DISPLAY 0.872340 (-6502 4775);
PAINT GREEN (-6502 4775);
DISPLAY INVISIBLE (-6502 4775);
FORCEADD TAP..1
(-6500 4425);
FORCEPROP 3 LASTPIN (-6550 4425) SIG_NAME P5E_CPU1_P1_RX_BUF_DP<13>
J 0
(-6540 4435);
DISPLAY 0.659574 (-6540 4435);
PAINT MONO (-6540 4435);
DISPLAY INVISIBLE (-6540 4435);
FORCEPROP 1 LASTPIN (-6550 4425) BN 13
J 0
(-6562 4433);
DISPLAY 0.680851 (-6562 4433);
PAINT GREEN (-6562 4433);
FORCEPROP 2 LAST CDS_LIB standard
J 0
(-6500 4425);
DISPLAY INVISIBLE (-6500 4425);
FORCEPROP 1 LAST BODY_TYPE PLUMBING
J 0
(-6500 4475);
DISPLAY 0.872340 (-6500 4475);
PAINT GREEN (-6500 4475);
DISPLAY INVISIBLE (-6500 4475);
FORCEPROP 1 LAST HDL_TAP TRUE
J 0
(-6175 4300);
DISPLAY 0.872340 (-6175 4300);
DISPLAY INVISIBLE (-6175 4300);
FORCEPROP 1 LAST PATH I14
J 0
(-6502 4425);
DISPLAY 0.872340 (-6502 4425);
PAINT GREEN (-6502 4425);
DISPLAY INVISIBLE (-6502 4425);
FORCEADD TAP..1
(-6300 4325);
FORCEPROP 3 LASTPIN (-6350 4325) SIG_NAME P5E_CPU1_P1_RX_BUF_DN<13>
J 0
(-6340 4335);
DISPLAY 0.659574 (-6340 4335);
PAINT MONO (-6340 4335);
DISPLAY INVISIBLE (-6340 4335);
FORCEPROP 1 LASTPIN (-6350 4325) BN 13
J 0
(-6362 4333);
DISPLAY 0.680851 (-6362 4333);
PAINT GREEN (-6362 4333);
FORCEPROP 2 LAST CDS_LIB standard
J 0
(-6300 4325);
DISPLAY INVISIBLE (-6300 4325);
FORCEPROP 1 LAST BODY_TYPE PLUMBING
J 0
(-6300 4375);
DISPLAY 0.872340 (-6300 4375);
PAINT GREEN (-6300 4375);
DISPLAY INVISIBLE (-6300 4375);
FORCEPROP 1 LAST HDL_TAP TRUE
J 0
(-5975 4200);
DISPLAY 0.872340 (-5975 4200);
DISPLAY INVISIBLE (-5975 4200);
FORCEPROP 1 LAST PATH I15
J 0
(-6302 4325);
DISPLAY 0.872340 (-6302 4325);
PAINT GREEN (-6302 4325);
DISPLAY INVISIBLE (-6302 4325);
FORCEADD TAP..1
(-6300 4675);
FORCEPROP 3 LASTPIN (-6350 4675) SIG_NAME P5E_CPU1_P1_RX_BUF_DN<14>
J 0
(-6340 4685);
DISPLAY 0.659574 (-6340 4685);
PAINT MONO (-6340 4685);
DISPLAY INVISIBLE (-6340 4685);
FORCEPROP 1 LASTPIN (-6350 4675) BN 14
J 0
(-6362 4683);
DISPLAY 0.680851 (-6362 4683);
PAINT GREEN (-6362 4683);
FORCEPROP 2 LAST CDS_LIB standard
J 0
(-6300 4675);
DISPLAY INVISIBLE (-6300 4675);
FORCEPROP 1 LAST BODY_TYPE PLUMBING
J 0
(-6300 4725);
DISPLAY 0.872340 (-6300 4725);
PAINT GREEN (-6300 4725);
DISPLAY INVISIBLE (-6300 4725);
FORCEPROP 1 LAST HDL_TAP TRUE
J 0
(-5975 4550);
DISPLAY 0.872340 (-5975 4550);
DISPLAY INVISIBLE (-5975 4550);
FORCEPROP 1 LAST PATH I16
J 0
(-6302 4675);
DISPLAY 0.872340 (-6302 4675);
PAINT GREEN (-6302 4675);
DISPLAY INVISIBLE (-6302 4675);
FORCEADD TAP..1
(-6300 5025);
FORCEPROP 3 LASTPIN (-6350 5025) SIG_NAME P5E_CPU1_P1_RX_BUF_DN<15>
J 0
(-6340 5035);
DISPLAY 0.659574 (-6340 5035);
PAINT MONO (-6340 5035);
DISPLAY INVISIBLE (-6340 5035);
FORCEPROP 1 LASTPIN (-6350 5025) BN 15
J 0
(-6362 5033);
DISPLAY 0.680851 (-6362 5033);
PAINT GREEN (-6362 5033);
FORCEPROP 2 LAST CDS_LIB standard
J 0
(-6300 5025);
DISPLAY INVISIBLE (-6300 5025);
FORCEPROP 1 LAST BODY_TYPE PLUMBING
J 0
(-6300 5075);
DISPLAY 0.872340 (-6300 5075);
PAINT GREEN (-6300 5075);
DISPLAY INVISIBLE (-6300 5075);
FORCEPROP 1 LAST HDL_TAP TRUE
J 0
(-5975 4900);
DISPLAY 0.872340 (-5975 4900);
DISPLAY INVISIBLE (-5975 4900);
FORCEPROP 1 LAST PATH I17
J 0
(-6302 5025);
DISPLAY 0.872340 (-6302 5025);
PAINT GREEN (-6302 5025);
DISPLAY INVISIBLE (-6302 5025);
FORCEADD OFFPAGE..1
R 2
(-5275 5150);
FORCEPROP 2 LAST $XR0 121 
J 0
(-5089 5150);
DISPLAY 0.638298 (-5089 5150);
PAINT MONO (-5089 5150);
FORCEPROP 2 LAST CDS_LIB standard
J 0
(-5275 5150);
DISPLAY INVISIBLE (-5275 5150);
FORCEPROP 1 LAST OFFPAGE TRUE
J 2
(-5600 5025);
DISPLAY 0.872340 (-5600 5025);
DISPLAY INVISIBLE (-5600 5025);
FORCEPROP 1 LAST COMMENT_BODY TRUE
J 2
(-5400 5050);
DISPLAY 0.872340 (-5400 5050);
PAINT GREEN (-5400 5050);
DISPLAY INVISIBLE (-5400 5050);
FORCEPROP 2 LAST PATH I18
J 0
(-5100 5225);
DISPLAY 0.680851 (-5100 5225);
DISPLAY INVISIBLE (-5100 5225);
FORCEADD OFFPAGE..1
R 2
(-5275 5225);
FORCEPROP 2 LAST $XR0 121 
J 0
(-5089 5225);
DISPLAY 0.638298 (-5089 5225);
PAINT MONO (-5089 5225);
FORCEPROP 2 LAST CDS_LIB standard
J 0
(-5275 5225);
DISPLAY INVISIBLE (-5275 5225);
FORCEPROP 1 LAST OFFPAGE TRUE
J 2
(-5600 5100);
DISPLAY 0.872340 (-5600 5100);
DISPLAY INVISIBLE (-5600 5100);
FORCEPROP 1 LAST COMMENT_BODY TRUE
J 2
(-5400 5125);
DISPLAY 0.872340 (-5400 5125);
PAINT GREEN (-5400 5125);
DISPLAY INVISIBLE (-5400 5125);
FORCEPROP 2 LAST PATH I19
J 0
(-5100 5300);
DISPLAY 0.680851 (-5100 5300);
DISPLAY INVISIBLE (-5100 5300);
FORCEADD TAP..1
(-6500 3025);
FORCEPROP 3 LASTPIN (-6550 3025) SIG_NAME P5E_CPU1_P1_RX_BUF_DP<9>
J 0
(-6540 3035);
DISPLAY 0.659574 (-6540 3035);
PAINT MONO (-6540 3035);
DISPLAY INVISIBLE (-6540 3035);
FORCEPROP 1 LASTPIN (-6550 3025) BN 9
J 0
(-6562 3033);
DISPLAY 0.680851 (-6562 3033);
PAINT GREEN (-6562 3033);
FORCEPROP 2 LAST CDS_LIB standard
J 0
(-6500 3025);
DISPLAY INVISIBLE (-6500 3025);
FORCEPROP 1 LAST BODY_TYPE PLUMBING
J 0
(-6500 3075);
DISPLAY 0.872340 (-6500 3075);
PAINT GREEN (-6500 3075);
DISPLAY INVISIBLE (-6500 3075);
FORCEPROP 1 LAST HDL_TAP TRUE
J 0
(-6175 2900);
DISPLAY 0.872340 (-6175 2900);
DISPLAY INVISIBLE (-6175 2900);
FORCEPROP 1 LAST PATH I2
J 0
(-6502 3025);
DISPLAY 0.872340 (-6502 3025);
PAINT GREEN (-6502 3025);
DISPLAY INVISIBLE (-6502 3025);
FORCEADD TAP..1
(-1850 2600);
FORCEPROP 3 LASTPIN (-1900 2600) SIG_NAME P5E_CPU1_P1_RX_BUF_DN<0>
J 0
(-1890 2610);
DISPLAY 0.659574 (-1890 2610);
PAINT MONO (-1890 2610);
DISPLAY INVISIBLE (-1890 2610);
FORCEPROP 1 LASTPIN (-1900 2600) BN 0
J 0
(-1912 2608);
DISPLAY 0.680851 (-1912 2608);
PAINT GREEN (-1912 2608);
FORCEPROP 2 LAST CDS_LIB standard
J 0
(-1850 2600);
DISPLAY INVISIBLE (-1850 2600);
FORCEPROP 1 LAST BODY_TYPE PLUMBING
J 0
(-1850 2650);
DISPLAY 0.872340 (-1850 2650);
PAINT GREEN (-1850 2650);
DISPLAY INVISIBLE (-1850 2650);
FORCEPROP 1 LAST HDL_TAP TRUE
J 0
(-1525 2475);
DISPLAY 0.872340 (-1525 2475);
DISPLAY INVISIBLE (-1525 2475);
FORCEPROP 1 LAST PATH I20
J 0
(-1852 2600);
DISPLAY 0.872340 (-1852 2600);
PAINT GREEN (-1852 2600);
DISPLAY INVISIBLE (-1852 2600);
FORCEADD TAP..1
(-2050 2700);
FORCEPROP 3 LASTPIN (-2100 2700) SIG_NAME P5E_CPU1_P1_RX_BUF_DP<0>
J 0
(-2090 2710);
DISPLAY 0.659574 (-2090 2710);
PAINT MONO (-2090 2710);
DISPLAY INVISIBLE (-2090 2710);
FORCEPROP 1 LASTPIN (-2100 2700) BN 0
J 0
(-2112 2708);
DISPLAY 0.680851 (-2112 2708);
PAINT GREEN (-2112 2708);
FORCEPROP 2 LAST CDS_LIB standard
J 0
(-2050 2700);
DISPLAY INVISIBLE (-2050 2700);
FORCEPROP 1 LAST BODY_TYPE PLUMBING
J 0
(-2050 2750);
DISPLAY 0.872340 (-2050 2750);
PAINT GREEN (-2050 2750);
DISPLAY INVISIBLE (-2050 2750);
FORCEPROP 1 LAST HDL_TAP TRUE
J 0
(-1725 2575);
DISPLAY 0.872340 (-1725 2575);
DISPLAY INVISIBLE (-1725 2575);
FORCEPROP 1 LAST PATH I21
J 0
(-2052 2700);
DISPLAY 0.872340 (-2052 2700);
PAINT GREEN (-2052 2700);
DISPLAY INVISIBLE (-2052 2700);
FORCEADD TAP..1
(-2050 3050);
FORCEPROP 3 LASTPIN (-2100 3050) SIG_NAME P5E_CPU1_P1_RX_BUF_DP<1>
J 0
(-2090 3060);
DISPLAY 0.659574 (-2090 3060);
PAINT MONO (-2090 3060);
DISPLAY INVISIBLE (-2090 3060);
FORCEPROP 1 LASTPIN (-2100 3050) BN 1
J 0
(-2112 3058);
DISPLAY 0.680851 (-2112 3058);
PAINT GREEN (-2112 3058);
FORCEPROP 2 LAST CDS_LIB standard
J 0
(-2050 3050);
DISPLAY INVISIBLE (-2050 3050);
FORCEPROP 1 LAST BODY_TYPE PLUMBING
J 0
(-2050 3100);
DISPLAY 0.872340 (-2050 3100);
PAINT GREEN (-2050 3100);
DISPLAY INVISIBLE (-2050 3100);
FORCEPROP 1 LAST HDL_TAP TRUE
J 0
(-1725 2925);
DISPLAY 0.872340 (-1725 2925);
DISPLAY INVISIBLE (-1725 2925);
FORCEPROP 1 LAST PATH I22
J 0
(-2052 3050);
DISPLAY 0.872340 (-2052 3050);
PAINT GREEN (-2052 3050);
DISPLAY INVISIBLE (-2052 3050);
FORCEADD TAP..1
(-1850 2950);
FORCEPROP 3 LASTPIN (-1900 2950) SIG_NAME P5E_CPU1_P1_RX_BUF_DN<1>
J 0
(-1890 2960);
DISPLAY 0.659574 (-1890 2960);
PAINT MONO (-1890 2960);
DISPLAY INVISIBLE (-1890 2960);
FORCEPROP 1 LASTPIN (-1900 2950) BN 1
J 0
(-1912 2958);
DISPLAY 0.680851 (-1912 2958);
PAINT GREEN (-1912 2958);
FORCEPROP 2 LAST CDS_LIB standard
J 0
(-1850 2950);
DISPLAY INVISIBLE (-1850 2950);
FORCEPROP 1 LAST BODY_TYPE PLUMBING
J 0
(-1850 3000);
DISPLAY 0.872340 (-1850 3000);
PAINT GREEN (-1850 3000);
DISPLAY INVISIBLE (-1850 3000);
FORCEPROP 1 LAST HDL_TAP TRUE
J 0
(-1525 2825);
DISPLAY 0.872340 (-1525 2825);
DISPLAY INVISIBLE (-1525 2825);
FORCEPROP 1 LAST PATH I23
J 0
(-1852 2950);
DISPLAY 0.872340 (-1852 2950);
PAINT GREEN (-1852 2950);
DISPLAY INVISIBLE (-1852 2950);
FORCEADD TAP..1
(-2050 3400);
FORCEPROP 3 LASTPIN (-2100 3400) SIG_NAME P5E_CPU1_P1_RX_BUF_DP<2>
J 0
(-2090 3410);
DISPLAY 0.659574 (-2090 3410);
PAINT MONO (-2090 3410);
DISPLAY INVISIBLE (-2090 3410);
FORCEPROP 1 LASTPIN (-2100 3400) BN 2
J 0
(-2112 3408);
DISPLAY 0.680851 (-2112 3408);
PAINT GREEN (-2112 3408);
FORCEPROP 2 LAST CDS_LIB standard
J 0
(-2050 3400);
DISPLAY INVISIBLE (-2050 3400);
FORCEPROP 1 LAST BODY_TYPE PLUMBING
J 0
(-2050 3450);
DISPLAY 0.872340 (-2050 3450);
PAINT GREEN (-2050 3450);
DISPLAY INVISIBLE (-2050 3450);
FORCEPROP 1 LAST HDL_TAP TRUE
J 0
(-1725 3275);
DISPLAY 0.872340 (-1725 3275);
DISPLAY INVISIBLE (-1725 3275);
FORCEPROP 1 LAST PATH I24
J 0
(-2052 3400);
DISPLAY 0.872340 (-2052 3400);
PAINT GREEN (-2052 3400);
DISPLAY INVISIBLE (-2052 3400);
FORCEADD TAP..1
(-1850 3300);
FORCEPROP 3 LASTPIN (-1900 3300) SIG_NAME P5E_CPU1_P1_RX_BUF_DN<2>
J 0
(-1890 3310);
DISPLAY 0.659574 (-1890 3310);
PAINT MONO (-1890 3310);
DISPLAY INVISIBLE (-1890 3310);
FORCEPROP 1 LASTPIN (-1900 3300) BN 2
J 0
(-1912 3308);
DISPLAY 0.680851 (-1912 3308);
PAINT GREEN (-1912 3308);
FORCEPROP 2 LAST CDS_LIB standard
J 0
(-1850 3300);
DISPLAY INVISIBLE (-1850 3300);
FORCEPROP 1 LAST BODY_TYPE PLUMBING
J 0
(-1850 3350);
DISPLAY 0.872340 (-1850 3350);
PAINT GREEN (-1850 3350);
DISPLAY INVISIBLE (-1850 3350);
FORCEPROP 1 LAST HDL_TAP TRUE
J 0
(-1525 3175);
DISPLAY 0.872340 (-1525 3175);
DISPLAY INVISIBLE (-1525 3175);
FORCEPROP 1 LAST PATH I25
J 0
(-1852 3300);
DISPLAY 0.872340 (-1852 3300);
PAINT GREEN (-1852 3300);
DISPLAY INVISIBLE (-1852 3300);
FORCEADD TAP..1
(-1850 3650);
FORCEPROP 3 LASTPIN (-1900 3650) SIG_NAME P5E_CPU1_P1_RX_BUF_DN<3>
J 0
(-1890 3660);
DISPLAY 0.659574 (-1890 3660);
PAINT MONO (-1890 3660);
DISPLAY INVISIBLE (-1890 3660);
FORCEPROP 1 LASTPIN (-1900 3650) BN 3
J 0
(-1912 3658);
DISPLAY 0.680851 (-1912 3658);
PAINT GREEN (-1912 3658);
FORCEPROP 2 LAST CDS_LIB standard
J 0
(-1850 3650);
DISPLAY INVISIBLE (-1850 3650);
FORCEPROP 1 LAST BODY_TYPE PLUMBING
J 0
(-1850 3700);
DISPLAY 0.872340 (-1850 3700);
PAINT GREEN (-1850 3700);
DISPLAY INVISIBLE (-1850 3700);
FORCEPROP 1 LAST HDL_TAP TRUE
J 0
(-1525 3525);
DISPLAY 0.872340 (-1525 3525);
DISPLAY INVISIBLE (-1525 3525);
FORCEPROP 1 LAST PATH I26
J 0
(-1852 3650);
DISPLAY 0.872340 (-1852 3650);
PAINT GREEN (-1852 3650);
DISPLAY INVISIBLE (-1852 3650);
FORCEADD TAP..1
(-2050 3750);
FORCEPROP 3 LASTPIN (-2100 3750) SIG_NAME P5E_CPU1_P1_RX_BUF_DP<3>
J 0
(-2090 3760);
DISPLAY 0.659574 (-2090 3760);
PAINT MONO (-2090 3760);
DISPLAY INVISIBLE (-2090 3760);
FORCEPROP 1 LASTPIN (-2100 3750) BN 3
J 0
(-2112 3758);
DISPLAY 0.680851 (-2112 3758);
PAINT GREEN (-2112 3758);
FORCEPROP 2 LAST CDS_LIB standard
J 0
(-2050 3750);
DISPLAY INVISIBLE (-2050 3750);
FORCEPROP 1 LAST BODY_TYPE PLUMBING
J 0
(-2050 3800);
DISPLAY 0.872340 (-2050 3800);
PAINT GREEN (-2050 3800);
DISPLAY INVISIBLE (-2050 3800);
FORCEPROP 1 LAST HDL_TAP TRUE
J 0
(-1725 3625);
DISPLAY 0.872340 (-1725 3625);
DISPLAY INVISIBLE (-1725 3625);
FORCEPROP 1 LAST PATH I27
J 0
(-2052 3750);
DISPLAY 0.872340 (-2052 3750);
PAINT GREEN (-2052 3750);
DISPLAY INVISIBLE (-2052 3750);
FORCEADD TAP..1
(-2050 4100);
FORCEPROP 3 LASTPIN (-2100 4100) SIG_NAME P5E_CPU1_P1_RX_BUF_DP<4>
J 0
(-2090 4110);
DISPLAY 0.659574 (-2090 4110);
PAINT MONO (-2090 4110);
DISPLAY INVISIBLE (-2090 4110);
FORCEPROP 1 LASTPIN (-2100 4100) BN 4
J 0
(-2112 4108);
DISPLAY 0.680851 (-2112 4108);
PAINT GREEN (-2112 4108);
FORCEPROP 2 LAST CDS_LIB standard
J 0
(-2050 4100);
DISPLAY INVISIBLE (-2050 4100);
FORCEPROP 1 LAST BODY_TYPE PLUMBING
J 0
(-2050 4150);
DISPLAY 0.872340 (-2050 4150);
PAINT GREEN (-2050 4150);
DISPLAY INVISIBLE (-2050 4150);
FORCEPROP 1 LAST HDL_TAP TRUE
J 0
(-1725 3975);
DISPLAY 0.872340 (-1725 3975);
DISPLAY INVISIBLE (-1725 3975);
FORCEPROP 1 LAST PATH I28
J 0
(-2052 4100);
DISPLAY 0.872340 (-2052 4100);
PAINT GREEN (-2052 4100);
DISPLAY INVISIBLE (-2052 4100);
FORCEADD TAP..1
(-1850 4000);
FORCEPROP 3 LASTPIN (-1900 4000) SIG_NAME P5E_CPU1_P1_RX_BUF_DN<4>
J 0
(-1890 4010);
DISPLAY 0.659574 (-1890 4010);
PAINT MONO (-1890 4010);
DISPLAY INVISIBLE (-1890 4010);
FORCEPROP 1 LASTPIN (-1900 4000) BN 4
J 0
(-1912 4008);
DISPLAY 0.680851 (-1912 4008);
PAINT GREEN (-1912 4008);
FORCEPROP 2 LAST CDS_LIB standard
J 0
(-1850 4000);
DISPLAY INVISIBLE (-1850 4000);
FORCEPROP 1 LAST BODY_TYPE PLUMBING
J 0
(-1850 4050);
DISPLAY 0.872340 (-1850 4050);
PAINT GREEN (-1850 4050);
DISPLAY INVISIBLE (-1850 4050);
FORCEPROP 1 LAST HDL_TAP TRUE
J 0
(-1525 3875);
DISPLAY 0.872340 (-1525 3875);
DISPLAY INVISIBLE (-1525 3875);
FORCEPROP 1 LAST PATH I29
J 0
(-1852 4000);
DISPLAY 0.872340 (-1852 4000);
PAINT GREEN (-1852 4000);
DISPLAY INVISIBLE (-1852 4000);
FORCEADD TAP..1
(-6500 2675);
FORCEPROP 3 LASTPIN (-6550 2675) SIG_NAME P5E_CPU1_P1_RX_BUF_DP<8>
J 0
(-6540 2685);
DISPLAY 0.659574 (-6540 2685);
PAINT MONO (-6540 2685);
DISPLAY INVISIBLE (-6540 2685);
FORCEPROP 1 LASTPIN (-6550 2675) BN 8
J 0
(-6562 2683);
DISPLAY 0.680851 (-6562 2683);
PAINT GREEN (-6562 2683);
FORCEPROP 2 LAST CDS_LIB standard
J 0
(-6500 2675);
DISPLAY INVISIBLE (-6500 2675);
FORCEPROP 1 LAST BODY_TYPE PLUMBING
J 0
(-6500 2725);
DISPLAY 0.872340 (-6500 2725);
PAINT GREEN (-6500 2725);
DISPLAY INVISIBLE (-6500 2725);
FORCEPROP 1 LAST HDL_TAP TRUE
J 0
(-6175 2550);
DISPLAY 0.872340 (-6175 2550);
DISPLAY INVISIBLE (-6175 2550);
FORCEPROP 1 LAST PATH I3
J 0
(-6502 2675);
DISPLAY 0.872340 (-6502 2675);
PAINT GREEN (-6502 2675);
DISPLAY INVISIBLE (-6502 2675);
FORCEADD TAP..1
(-2050 4450);
FORCEPROP 3 LASTPIN (-2100 4450) SIG_NAME P5E_CPU1_P1_RX_BUF_DP<5>
J 0
(-2090 4460);
DISPLAY 0.659574 (-2090 4460);
PAINT MONO (-2090 4460);
DISPLAY INVISIBLE (-2090 4460);
FORCEPROP 1 LASTPIN (-2100 4450) BN 5
J 0
(-2112 4458);
DISPLAY 0.680851 (-2112 4458);
PAINT GREEN (-2112 4458);
FORCEPROP 2 LAST CDS_LIB standard
J 0
(-2050 4450);
DISPLAY INVISIBLE (-2050 4450);
FORCEPROP 1 LAST BODY_TYPE PLUMBING
J 0
(-2050 4500);
DISPLAY 0.872340 (-2050 4500);
PAINT GREEN (-2050 4500);
DISPLAY INVISIBLE (-2050 4500);
FORCEPROP 1 LAST HDL_TAP TRUE
J 0
(-1725 4325);
DISPLAY 0.872340 (-1725 4325);
DISPLAY INVISIBLE (-1725 4325);
FORCEPROP 1 LAST PATH I30
J 0
(-2052 4450);
DISPLAY 0.872340 (-2052 4450);
PAINT GREEN (-2052 4450);
DISPLAY INVISIBLE (-2052 4450);
FORCEADD TAP..1
(-1850 4350);
FORCEPROP 3 LASTPIN (-1900 4350) SIG_NAME P5E_CPU1_P1_RX_BUF_DN<5>
J 0
(-1890 4360);
DISPLAY 0.659574 (-1890 4360);
PAINT MONO (-1890 4360);
DISPLAY INVISIBLE (-1890 4360);
FORCEPROP 1 LASTPIN (-1900 4350) BN 5
J 0
(-1912 4358);
DISPLAY 0.680851 (-1912 4358);
PAINT GREEN (-1912 4358);
FORCEPROP 2 LAST CDS_LIB standard
J 0
(-1850 4350);
DISPLAY INVISIBLE (-1850 4350);
FORCEPROP 1 LAST BODY_TYPE PLUMBING
J 0
(-1850 4400);
DISPLAY 0.872340 (-1850 4400);
PAINT GREEN (-1850 4400);
DISPLAY INVISIBLE (-1850 4400);
FORCEPROP 1 LAST HDL_TAP TRUE
J 0
(-1525 4225);
DISPLAY 0.872340 (-1525 4225);
DISPLAY INVISIBLE (-1525 4225);
FORCEPROP 1 LAST PATH I31
J 0
(-1852 4350);
DISPLAY 0.872340 (-1852 4350);
PAINT GREEN (-1852 4350);
DISPLAY INVISIBLE (-1852 4350);
FORCEADD TAP..1
(-1850 4700);
FORCEPROP 3 LASTPIN (-1900 4700) SIG_NAME P5E_CPU1_P1_RX_BUF_DN<6>
J 0
(-1890 4710);
DISPLAY 0.659574 (-1890 4710);
PAINT MONO (-1890 4710);
DISPLAY INVISIBLE (-1890 4710);
FORCEPROP 1 LASTPIN (-1900 4700) BN 6
J 0
(-1912 4708);
DISPLAY 0.680851 (-1912 4708);
PAINT GREEN (-1912 4708);
FORCEPROP 2 LAST CDS_LIB standard
J 0
(-1850 4700);
DISPLAY INVISIBLE (-1850 4700);
FORCEPROP 1 LAST BODY_TYPE PLUMBING
J 0
(-1850 4750);
DISPLAY 0.872340 (-1850 4750);
PAINT GREEN (-1850 4750);
DISPLAY INVISIBLE (-1850 4750);
FORCEPROP 1 LAST HDL_TAP TRUE
J 0
(-1525 4575);
DISPLAY 0.872340 (-1525 4575);
DISPLAY INVISIBLE (-1525 4575);
FORCEPROP 1 LAST PATH I32
J 0
(-1852 4700);
DISPLAY 0.872340 (-1852 4700);
PAINT GREEN (-1852 4700);
DISPLAY INVISIBLE (-1852 4700);
FORCEADD TAP..1
(-2050 4800);
FORCEPROP 3 LASTPIN (-2100 4800) SIG_NAME P5E_CPU1_P1_RX_BUF_DP<6>
J 0
(-2090 4810);
DISPLAY 0.659574 (-2090 4810);
PAINT MONO (-2090 4810);
DISPLAY INVISIBLE (-2090 4810);
FORCEPROP 1 LASTPIN (-2100 4800) BN 6
J 0
(-2112 4808);
DISPLAY 0.680851 (-2112 4808);
PAINT GREEN (-2112 4808);
FORCEPROP 2 LAST CDS_LIB standard
J 0
(-2050 4800);
DISPLAY INVISIBLE (-2050 4800);
FORCEPROP 1 LAST BODY_TYPE PLUMBING
J 0
(-2050 4850);
DISPLAY 0.872340 (-2050 4850);
PAINT GREEN (-2050 4850);
DISPLAY INVISIBLE (-2050 4850);
FORCEPROP 1 LAST HDL_TAP TRUE
J 0
(-1725 4675);
DISPLAY 0.872340 (-1725 4675);
DISPLAY INVISIBLE (-1725 4675);
FORCEPROP 1 LAST PATH I33
J 0
(-2052 4800);
DISPLAY 0.872340 (-2052 4800);
PAINT GREEN (-2052 4800);
DISPLAY INVISIBLE (-2052 4800);
FORCEADD TAP..1
(-2050 5150);
FORCEPROP 3 LASTPIN (-2100 5150) SIG_NAME P5E_CPU1_P1_RX_BUF_DP<7>
J 0
(-2090 5160);
DISPLAY 0.659574 (-2090 5160);
PAINT MONO (-2090 5160);
DISPLAY INVISIBLE (-2090 5160);
FORCEPROP 1 LASTPIN (-2100 5150) BN 7
J 0
(-2112 5158);
DISPLAY 0.680851 (-2112 5158);
PAINT GREEN (-2112 5158);
FORCEPROP 2 LAST CDS_LIB standard
J 0
(-2050 5150);
DISPLAY INVISIBLE (-2050 5150);
FORCEPROP 1 LAST BODY_TYPE PLUMBING
J 0
(-2050 5200);
DISPLAY 0.872340 (-2050 5200);
PAINT GREEN (-2050 5200);
DISPLAY INVISIBLE (-2050 5200);
FORCEPROP 1 LAST HDL_TAP TRUE
J 0
(-1725 5025);
DISPLAY 0.872340 (-1725 5025);
DISPLAY INVISIBLE (-1725 5025);
FORCEPROP 1 LAST PATH I34
J 0
(-2052 5150);
DISPLAY 0.872340 (-2052 5150);
PAINT GREEN (-2052 5150);
DISPLAY INVISIBLE (-2052 5150);
FORCEADD TAP..1
(-1850 5050);
FORCEPROP 3 LASTPIN (-1900 5050) SIG_NAME P5E_CPU1_P1_RX_BUF_DN<7>
J 0
(-1890 5060);
DISPLAY 0.659574 (-1890 5060);
PAINT MONO (-1890 5060);
DISPLAY INVISIBLE (-1890 5060);
FORCEPROP 1 LASTPIN (-1900 5050) BN 7
J 0
(-1912 5058);
DISPLAY 0.680851 (-1912 5058);
PAINT GREEN (-1912 5058);
FORCEPROP 2 LAST CDS_LIB standard
J 0
(-1850 5050);
DISPLAY INVISIBLE (-1850 5050);
FORCEPROP 1 LAST BODY_TYPE PLUMBING
J 0
(-1850 5100);
DISPLAY 0.872340 (-1850 5100);
PAINT GREEN (-1850 5100);
DISPLAY INVISIBLE (-1850 5100);
FORCEPROP 1 LAST HDL_TAP TRUE
J 0
(-1525 4925);
DISPLAY 0.872340 (-1525 4925);
DISPLAY INVISIBLE (-1525 4925);
FORCEPROP 1 LAST PATH I35
J 0
(-1852 5050);
DISPLAY 0.872340 (-1852 5050);
PAINT GREEN (-1852 5050);
DISPLAY INVISIBLE (-1852 5050);
FORCEADD OFFPAGE..1
R 2
(-825 5175);
FORCEPROP 2 LAST $XR0 122 
J 0
(-639 5175);
DISPLAY 0.638298 (-639 5175);
PAINT MONO (-639 5175);
FORCEPROP 2 LAST CDS_LIB standard
J 0
(-825 5175);
DISPLAY INVISIBLE (-825 5175);
FORCEPROP 1 LAST OFFPAGE TRUE
J 2
(-1150 5050);
DISPLAY 0.872340 (-1150 5050);
DISPLAY INVISIBLE (-1150 5050);
FORCEPROP 1 LAST COMMENT_BODY TRUE
J 2
(-950 5075);
DISPLAY 0.872340 (-950 5075);
PAINT GREEN (-950 5075);
DISPLAY INVISIBLE (-950 5075);
FORCEPROP 2 LAST PATH I36
J 0
(-650 5250);
DISPLAY 0.680851 (-650 5250);
DISPLAY INVISIBLE (-650 5250);
FORCEADD OFFPAGE..1
R 2
(-825 5250);
FORCEPROP 2 LAST $XR0 122 
J 0
(-639 5250);
DISPLAY 0.638298 (-639 5250);
PAINT MONO (-639 5250);
FORCEPROP 2 LAST CDS_LIB standard
J 0
(-825 5250);
DISPLAY INVISIBLE (-825 5250);
FORCEPROP 1 LAST OFFPAGE TRUE
J 2
(-1150 5125);
DISPLAY 0.872340 (-1150 5125);
DISPLAY INVISIBLE (-1150 5125);
FORCEPROP 1 LAST COMMENT_BODY TRUE
J 2
(-950 5150);
DISPLAY 0.872340 (-950 5150);
PAINT GREEN (-950 5150);
DISPLAY INVISIBLE (-950 5150);
FORCEPROP 2 LAST PATH I37
J 0
(-650 5325);
DISPLAY 0.680851 (-650 5325);
DISPLAY INVISIBLE (-650 5325);
FORCEADD PT5161LRS..2
(-3075 3900);
FORCEPROP 1 LAST LOCATION U6015
J 0
(-3425 5525);
DISPLAY 0.723404 (-3425 5525);
PAINT GREEN (-3425 5525);
FORCEPROP 0 LAST $SEC 2
J 0
(-3425 5675);
DISPLAY 0.680851 (-3425 5675);
PAINT MONO (-3425 5675);
DISPLAY INVISIBLE (-3425 5675);
FORCEPROP 0 LAST CDS_SEC 2
J 0
(-3425 5675);
DISPLAY 0.680851 (-3425 5675);
DISPLAY INVISIBLE (-3425 5675);
FORCEPROP 0 LASTPIN (-2625 5050) $PN CJ2
J 0
(-2615 5060);
DISPLAY 0.680851 (-2615 5060);
PAINT MONO (-2615 5060);
FORCEPROP 0 LASTPIN (-2625 4700) $PN CT2
J 0
(-2615 4710);
DISPLAY 0.680851 (-2615 4710);
PAINT MONO (-2615 4710);
FORCEPROP 0 LASTPIN (-2625 4350) $PN DC2
J 0
(-2615 4360);
DISPLAY 0.680851 (-2615 4360);
PAINT MONO (-2615 4360);
FORCEPROP 0 LASTPIN (-2625 4000) $PN DK2
J 0
(-2615 4010);
DISPLAY 0.680851 (-2615 4010);
PAINT MONO (-2615 4010);
FORCEPROP 0 LASTPIN (-2625 3650) $PN DU2
J 0
(-2615 3660);
DISPLAY 0.680851 (-2615 3660);
PAINT MONO (-2615 3660);
FORCEPROP 0 LASTPIN (-2625 3300) $PN ED2
J 0
(-2615 3310);
DISPLAY 0.680851 (-2615 3310);
PAINT MONO (-2615 3310);
FORCEPROP 0 LASTPIN (-2625 2950) $PN EL2
J 0
(-2615 2960);
DISPLAY 0.680851 (-2615 2960);
PAINT MONO (-2615 2960);
FORCEPROP 0 LASTPIN (-2625 2600) $PN EV2
J 0
(-2615 2610);
DISPLAY 0.680851 (-2615 2610);
PAINT MONO (-2615 2610);
FORCEPROP 0 LASTPIN (-2625 5150) $PN CL1
J 0
(-2615 5160);
DISPLAY 0.680851 (-2615 5160);
PAINT MONO (-2615 5160);
FORCEPROP 0 LASTPIN (-2625 4800) $PN CV1
J 0
(-2615 4810);
DISPLAY 0.680851 (-2615 4810);
PAINT MONO (-2615 4810);
FORCEPROP 0 LASTPIN (-2625 4450) $PN DE1
J 0
(-2615 4460);
DISPLAY 0.680851 (-2615 4460);
PAINT MONO (-2615 4460);
FORCEPROP 0 LASTPIN (-2625 4100) $PN DM1
J 0
(-2615 4110);
DISPLAY 0.680851 (-2615 4110);
PAINT MONO (-2615 4110);
FORCEPROP 0 LASTPIN (-2625 3750) $PN DW1
J 0
(-2615 3760);
DISPLAY 0.680851 (-2615 3760);
PAINT MONO (-2615 3760);
FORCEPROP 0 LASTPIN (-2625 3400) $PN EF1
J 0
(-2615 3410);
DISPLAY 0.680851 (-2615 3410);
PAINT MONO (-2615 3410);
FORCEPROP 0 LASTPIN (-2625 3050) $PN EN1
J 0
(-2615 3060);
DISPLAY 0.680851 (-2615 3060);
PAINT MONO (-2615 3060);
FORCEPROP 0 LASTPIN (-2625 2700) $PN EY1
J 0
(-2615 2710);
DISPLAY 0.680851 (-2615 2710);
PAINT MONO (-2615 2710);
FORCEPROP 2 LAST VALUE PT5161LRS
J 0
(-3425 5575);
DISPLAY 0.680851 (-3425 5575);
FORCEPROP 1 LAST MATERIAL IC
J 0
(-3425 5375);
DISPLAY 0.723404 (-3425 5375);
PAINT GREEN (-3425 5375);
FORCEPROP 2 LAST PART_TYPE SMLF
J 0
(-3425 5625);
DISPLAY 0.680851 (-3425 5625);
FORCEPROP 1 LAST NEEDS_NO_SIZE TRUE
J 0
(-3075 3900);
DISPLAY 0.723404 (-3075 3900);
PAINT GREEN (-3075 3900);
DISPLAY INVISIBLE (-3075 3900);
FORCEPROP 1 LAST CDS_LMAN_SYM_OUTLINE -350,1450,300,-1400
J 0
(-3075 3900);
DISPLAY 0.468085 (-3075 3900);
PAINT GREEN (-3075 3900);
DISPLAY INVISIBLE (-3075 3900);
FORCEPROP 2 LAST CDS_LIB pure_quanta
J 0
(-3075 3900);
DISPLAY INVISIBLE (-3075 3900);
FORCEPROP 1 LAST PATH I38
J 0
(-3075 3900);
DISPLAY 0.723404 (-3075 3900);
PAINT GREEN (-3075 3900);
DISPLAY INVISIBLE (-3075 3900);
FORCEPROP 1 LAST PART_NUMBER AJ051610U03
J 0
(-3425 5450);
DISPLAY 0.723404 (-3425 5450);
PAINT GREEN (-3425 5450);
DISPLAY INVISIBLE (-3425 5450);
FORCEADD TAP..1
(-6300 2575);
FORCEPROP 3 LASTPIN (-6350 2575) SIG_NAME P5E_CPU1_P1_RX_BUF_DN<8>
J 0
(-6340 2585);
DISPLAY 0.659574 (-6340 2585);
PAINT MONO (-6340 2585);
DISPLAY INVISIBLE (-6340 2585);
FORCEPROP 1 LASTPIN (-6350 2575) BN 8
J 0
(-6362 2583);
DISPLAY 0.680851 (-6362 2583);
PAINT GREEN (-6362 2583);
FORCEPROP 2 LAST CDS_LIB standard
J 0
(-6300 2575);
DISPLAY INVISIBLE (-6300 2575);
FORCEPROP 1 LAST BODY_TYPE PLUMBING
J 0
(-6300 2625);
DISPLAY 0.872340 (-6300 2625);
PAINT GREEN (-6300 2625);
DISPLAY INVISIBLE (-6300 2625);
FORCEPROP 1 LAST HDL_TAP TRUE
J 0
(-5975 2450);
DISPLAY 0.872340 (-5975 2450);
DISPLAY INVISIBLE (-5975 2450);
FORCEPROP 1 LAST PATH I4
J 0
(-6302 2575);
DISPLAY 0.872340 (-6302 2575);
PAINT GREEN (-6302 2575);
DISPLAY INVISIBLE (-6302 2575);
FORCEADD TAP..1
(-6300 2925);
FORCEPROP 3 LASTPIN (-6350 2925) SIG_NAME P5E_CPU1_P1_RX_BUF_DN<9>
J 0
(-6340 2935);
DISPLAY 0.659574 (-6340 2935);
PAINT MONO (-6340 2935);
DISPLAY INVISIBLE (-6340 2935);
FORCEPROP 1 LASTPIN (-6350 2925) BN 9
J 0
(-6362 2933);
DISPLAY 0.680851 (-6362 2933);
PAINT GREEN (-6362 2933);
FORCEPROP 2 LAST CDS_LIB standard
J 0
(-6300 2925);
DISPLAY INVISIBLE (-6300 2925);
FORCEPROP 1 LAST BODY_TYPE PLUMBING
J 0
(-6300 2975);
DISPLAY 0.872340 (-6300 2975);
PAINT GREEN (-6300 2975);
DISPLAY INVISIBLE (-6300 2975);
FORCEPROP 1 LAST HDL_TAP TRUE
J 0
(-5975 2800);
DISPLAY 0.872340 (-5975 2800);
DISPLAY INVISIBLE (-5975 2800);
FORCEPROP 1 LAST PATH I5
J 0
(-6302 2925);
DISPLAY 0.872340 (-6302 2925);
PAINT GREEN (-6302 2925);
DISPLAY INVISIBLE (-6302 2925);
FORCEADD TAP..1
(-6500 3725);
FORCEPROP 3 LASTPIN (-6550 3725) SIG_NAME P5E_CPU1_P1_RX_BUF_DP<11>
J 0
(-6540 3735);
DISPLAY 0.659574 (-6540 3735);
PAINT MONO (-6540 3735);
DISPLAY INVISIBLE (-6540 3735);
FORCEPROP 1 LASTPIN (-6550 3725) BN 11
J 0
(-6562 3733);
DISPLAY 0.680851 (-6562 3733);
PAINT GREEN (-6562 3733);
FORCEPROP 2 LAST CDS_LIB standard
J 0
(-6500 3725);
DISPLAY INVISIBLE (-6500 3725);
FORCEPROP 1 LAST BODY_TYPE PLUMBING
J 0
(-6500 3775);
DISPLAY 0.872340 (-6500 3775);
PAINT GREEN (-6500 3775);
DISPLAY INVISIBLE (-6500 3775);
FORCEPROP 1 LAST HDL_TAP TRUE
J 0
(-6175 3600);
DISPLAY 0.872340 (-6175 3600);
DISPLAY INVISIBLE (-6175 3600);
FORCEPROP 1 LAST PATH I6
J 0
(-6502 3725);
DISPLAY 0.872340 (-6502 3725);
PAINT GREEN (-6502 3725);
DISPLAY INVISIBLE (-6502 3725);
FORCEADD TAP..1
(-6500 3375);
FORCEPROP 3 LASTPIN (-6550 3375) SIG_NAME P5E_CPU1_P1_RX_BUF_DP<10>
J 0
(-6540 3385);
DISPLAY 0.659574 (-6540 3385);
PAINT MONO (-6540 3385);
DISPLAY INVISIBLE (-6540 3385);
FORCEPROP 1 LASTPIN (-6550 3375) BN 10
J 0
(-6562 3383);
DISPLAY 0.680851 (-6562 3383);
PAINT GREEN (-6562 3383);
FORCEPROP 2 LAST CDS_LIB standard
J 0
(-6500 3375);
DISPLAY INVISIBLE (-6500 3375);
FORCEPROP 1 LAST BODY_TYPE PLUMBING
J 0
(-6500 3425);
DISPLAY 0.872340 (-6500 3425);
PAINT GREEN (-6500 3425);
DISPLAY INVISIBLE (-6500 3425);
FORCEPROP 1 LAST HDL_TAP TRUE
J 0
(-6175 3250);
DISPLAY 0.872340 (-6175 3250);
DISPLAY INVISIBLE (-6175 3250);
FORCEPROP 1 LAST PATH I7
J 0
(-6502 3375);
DISPLAY 0.872340 (-6502 3375);
PAINT GREEN (-6502 3375);
DISPLAY INVISIBLE (-6502 3375);
FORCEADD TAP..1
(-6500 4075);
FORCEPROP 3 LASTPIN (-6550 4075) SIG_NAME P5E_CPU1_P1_RX_BUF_DP<12>
J 0
(-6540 4085);
DISPLAY 0.659574 (-6540 4085);
PAINT MONO (-6540 4085);
DISPLAY INVISIBLE (-6540 4085);
FORCEPROP 1 LASTPIN (-6550 4075) BN 12
J 0
(-6562 4083);
DISPLAY 0.680851 (-6562 4083);
PAINT GREEN (-6562 4083);
FORCEPROP 2 LAST CDS_LIB standard
J 0
(-6500 4075);
DISPLAY INVISIBLE (-6500 4075);
FORCEPROP 1 LAST BODY_TYPE PLUMBING
J 0
(-6500 4125);
DISPLAY 0.872340 (-6500 4125);
PAINT GREEN (-6500 4125);
DISPLAY INVISIBLE (-6500 4125);
FORCEPROP 1 LAST HDL_TAP TRUE
J 0
(-6175 3950);
DISPLAY 0.872340 (-6175 3950);
DISPLAY INVISIBLE (-6175 3950);
FORCEPROP 1 LAST PATH I8
J 0
(-6502 4075);
DISPLAY 0.872340 (-6502 4075);
PAINT GREEN (-6502 4075);
DISPLAY INVISIBLE (-6502 4075);
FORCEADD TAP..1
(-6300 3275);
FORCEPROP 3 LASTPIN (-6350 3275) SIG_NAME P5E_CPU1_P1_RX_BUF_DN<10>
J 0
(-6340 3285);
DISPLAY 0.659574 (-6340 3285);
PAINT MONO (-6340 3285);
DISPLAY INVISIBLE (-6340 3285);
FORCEPROP 1 LASTPIN (-6350 3275) BN 10
J 0
(-6362 3283);
DISPLAY 0.680851 (-6362 3283);
PAINT GREEN (-6362 3283);
FORCEPROP 2 LAST CDS_LIB standard
J 0
(-6300 3275);
DISPLAY INVISIBLE (-6300 3275);
FORCEPROP 1 LAST BODY_TYPE PLUMBING
J 0
(-6300 3325);
DISPLAY 0.872340 (-6300 3325);
PAINT GREEN (-6300 3325);
DISPLAY INVISIBLE (-6300 3325);
FORCEPROP 1 LAST HDL_TAP TRUE
J 0
(-5975 3150);
DISPLAY 0.872340 (-5975 3150);
DISPLAY INVISIBLE (-5975 3150);
FORCEPROP 1 LAST PATH I9
J 0
(-6302 3275);
DISPLAY 0.872340 (-6302 3275);
PAINT GREEN (-6302 3275);
DISPLAY INVISIBLE (-6302 3275);
FORCEADD QUANTA_TITLE_BLOCK_C..1
(0 0);
FORCEPROP 0 LAST CDS_CON_LAST_MODIFIED Thu Sep 14 16:12:50 2023
J 0
(-1885 15);
DISPLAY INVISIBLE (-1885 15);
FORCEPROP 1 LAST CUSTOM_TXT_CDS <CON_LAST_MODIFIED>
J 0
(-1885 15);
DISPLAY 0.978723 (-1885 15);
FORCEPROP 2 LAST CUSTOM_TXT_CDS <XR_PAGE_TITLE>
J 0
(-7890 5250);
DISPLAY 0.638298 (-7890 5250);
PAINT PINK (-7890 5250);
DISPLAY INVISIBLE (-7890 5250);
FORCEPROP 1 LAST CUSTOM_TXT_CDS <NAME_2>
J 0
(-3175 50);
FORCEPROP 1 LAST CUSTOM_TXT_CDS <NAME_1>
J 0
(-3175 175);
FORCEPROP 1 LAST CUSTOM_TXT_CDS <Q_NUMBER>
J 0
(-1403 103);
DISPLAY 1.212766 (-1403 103);
FORCEPROP 1 LAST CUSTOM_TXT_CDS <Q_PROJ>
J 0
(-2382 102);
DISPLAY 1.212766 (-2382 102);
FORCEPROP 1 LAST CUSTOM_TXT_CDS <Q_REV>
J 0
(-184 103);
DISPLAY 1.212766 (-184 103);
FORCEPROP 1 LAST CUSTOM_TXT_CDS <CON_PAGE_NUM> OF <CON_TOTAL_PAGES>
J 0
(-446 18);
DISPLAY 0.978723 (-446 18);
FORCEPROP 1 LAST Q_TITLE RETIMER_CPU1_P1(3)
J 0
(-9366 26);
DISPLAY 2.446809 (-9366 26);
PAINT GREEN (-9366 26);
FORCEPROP 2 LAST CDS_LIB pure_quanta
J 0
(0 0);
DISPLAY INVISIBLE (0 0);
FORCEPROP 1 LAST CDS_LMAN_SYM_OUTLINE -9475,6775,100,-125
J 0
(0 0);
DISPLAY 0.468085 (0 0);
PAINT GREEN (0 0);
DISPLAY INVISIBLE (0 0);
FORCEPROP 2 LAST PAGE_BORDER TRUE
J 0
(-7890 5250);
DISPLAY 0.638298 (-7890 5250);
PAINT PINK (-7890 5250);
DISPLAY INVISIBLE (-7890 5250);
FORCEPROP 2 LAST CDS_XR_PAGE_TITLE CR-330 : @T6G_MB_LIB.T6G(SCH_1):PAGE330
J 0
(-7890 5250);
DISPLAY 0.638298 (-7890 5250);
PAINT PINK (-7890 5250);
DISPLAY INVISIBLE (-7890 5250);
FORCEPROP 1 LAST Q_DEPT BU9
J 1
(-3763 49);
DISPLAY 1.957447 (-3763 49);
PAINT GREEN (-3763 49);
DISPLAY INVISIBLE (-3763 49);
FORCEPROP 1 LAST COMMENT_BODY TRUE
J 0
(12 -13);
DISPLAY 0.978723 (12 -13);
PAINT GREEN (12 -13);
DISPLAY INVISIBLE (12 -13);
WIRE 17 -1 (-1800 3675)(-1800 4025);
WIRE 17 -1 (-1800 3675)(-1800 3325);
WIRE 17 -1 (-1800 4375)(-1800 4025);
WIRE 17 -1 (-1800 4725)(-1800 4375);
WIRE 17 -1 (-1800 3325)(-1800 2975);
WIRE 17 -1 (-1800 2975)(-1800 2625);
WIRE 17 -1 (-1800 5075)(-1800 4725);
WIRE 17 -1 (-1800 5175)(-1800 5075);
WIRE 17 -1 (-1800 5175)(-875 5175);
FORCEPROP 2 LAST SIG_NAME P5E_CPU1_P1_RX_BUF_DN<7:0>
J 0
(-1735 5185);
DISPLAY 0.680851 (-1735 5185);
PAINT WHITE (-1735 5185);
WIRE 17 -1 (-2000 5175)(-2000 4825);
WIRE 17 -1 (-2000 5250)(-2000 5175);
WIRE 17 -1 (-2000 4825)(-2000 4475);
WIRE 17 -1 (-2000 4475)(-2000 4125);
WIRE 17 -1 (-2000 5250)(-875 5250);
FORCEPROP 2 LAST SIG_NAME P5E_CPU1_P1_RX_BUF_DP<7:0>
J 0
(-1735 5260);
DISPLAY 0.680851 (-1735 5260);
PAINT WHITE (-1735 5260);
WIRE 17 -1 (-6250 3650)(-6250 3300);
WIRE 17 -1 (-6250 3650)(-6250 4000);
WIRE 17 -1 (-6250 3300)(-6250 2950);
WIRE 17 -1 (-6250 2950)(-6250 2600);
WIRE 17 -1 (-6250 4350)(-6250 4000);
WIRE 17 -1 (-6250 4700)(-6250 4350);
WIRE 17 -1 (-6250 5050)(-6250 4700);
WIRE 17 -1 (-6250 5150)(-6250 5050);
WIRE 17 -1 (-6250 5150)(-5325 5150);
FORCEPROP 2 LAST SIG_NAME P5E_CPU1_P1_RX_BUF_DN<15:8>
J 0
(-6185 5160);
DISPLAY 0.680851 (-6185 5160);
PAINT WHITE (-6185 5160);
WIRE 17 -1 (-2000 3775)(-2000 4125);
WIRE 17 -1 (-2000 3775)(-2000 3425);
WIRE 17 -1 (-2000 3425)(-2000 3075);
WIRE 17 -1 (-2000 3075)(-2000 2725);
WIRE 17 -1 (-6450 5225)(-6450 5150);
WIRE 17 -1 (-6450 5225)(-5325 5225);
FORCEPROP 2 LAST SIG_NAME P5E_CPU1_P1_RX_BUF_DP<15:8>
J 0
(-6185 5235);
DISPLAY 0.680851 (-6185 5235);
PAINT WHITE (-6185 5235);
WIRE 17 -1 (-6450 3750)(-6450 3400);
WIRE 17 -1 (-6450 3750)(-6450 4100);
WIRE 17 -1 (-6450 3400)(-6450 3050);
WIRE 17 -1 (-6450 3050)(-6450 2700);
WIRE 17 -1 (-6450 4450)(-6450 4100);
WIRE 17 -1 (-6450 4800)(-6450 4450);
WIRE 17 -1 (-6450 5150)(-6450 4800);
WIRE 16 -1 (-7075 3725)(-6550 3725);
WIRE 16 -1 (-2625 3050)(-2100 3050);
WIRE 16 -1 (-2625 3400)(-2100 3400);
WIRE 16 -1 (-7075 3025)(-6550 3025);
WIRE 16 -1 (-7075 4075)(-6550 4075);
WIRE 16 -1 (-7075 4425)(-6550 4425);
WIRE 16 -1 (-7075 4775)(-6550 4775);
WIRE 16 -1 (-7075 2675)(-6550 2675);
WIRE 16 -1 (-7075 2925)(-6350 2925);
WIRE 16 -1 (-7075 3375)(-6550 3375);
WIRE 16 -1 (-7075 3625)(-6350 3625);
WIRE 16 -1 (-7075 4325)(-6350 4325);
WIRE 16 -1 (-7075 2575)(-6350 2575);
WIRE 16 -1 (-7075 5125)(-6550 5125);
WIRE 16 -1 (-2625 2700)(-2100 2700);
WIRE 16 -1 (-2625 2950)(-1900 2950);
WIRE 16 -1 (-2625 3750)(-2100 3750);
WIRE 16 -1 (-2625 4100)(-2100 4100);
WIRE 16 -1 (-2625 4450)(-2100 4450);
WIRE 16 -1 (-2625 2600)(-1900 2600);
WIRE 16 -1 (-2625 5150)(-2100 5150);
WIRE 16 -1 (-7075 5025)(-6350 5025);
WIRE 16 -1 (-7075 4675)(-6350 4675);
WIRE 16 -1 (-7075 3975)(-6350 3975);
WIRE 16 -1 (-7075 3275)(-6350 3275);
WIRE 16 -1 (-2625 5050)(-1900 5050);
WIRE 16 -1 (-2625 4800)(-2100 4800);
WIRE 16 -1 (-2625 4700)(-1900 4700);
WIRE 16 -1 (-2625 4350)(-1900 4350);
WIRE 16 -1 (-2625 4000)(-1900 4000);
WIRE 16 -1 (-2625 3300)(-1900 3300);
WIRE 16 -1 (-2625 3650)(-1900 3650);
FORCENOTE
EXAMAX TO RETIMER
(-3350 1725) 0;
DISPLAY LEFT (-3350 1725);
DISPLAY 3.148936 (-3350 1725);
FORCENOTE
EXAMAX TO RETIMER
(-7900 1750) 0;
DISPLAY LEFT (-7900 1750);
DISPLAY 3.148936 (-7900 1750);
FORCENOTE
P5E_CPU1_P1_RX_BUF_DP/DN<0-15> LANE REVERSAL
(-9025 6350) 0;
DISPLAY LEFT (-9025 6350);
DISPLAY 2.000000 (-9025 6350);
QUIT
